(kicad_pcb
	(version 20260206)
	(generator "pcbnew")
	(generator_version "10.0")
	(general
		(thickness 1.6)
		(legacy_teardrops no)
	)
	(paper "A4")
	(title_block
		(title "01162023_DA0F0TEBIF0_F0T_Expander_BD_F_brd_V02_OCP.brd")
		(comment 1 "Grand Teton / footprints 7121-7128 of 9728")
	)
	(layers
		(0 "F.Cu" signal "TOP")
		(4 "In1.Cu" signal "GND")
		(6 "In2.Cu" signal "VCC")
		(8 "In3.Cu" signal "VCC1")
		(10 "In4.Cu" signal "GND1")
		(12 "In5.Cu" signal "IN1")
		(14 "In6.Cu" signal "GND2")
		(16 "In7.Cu" signal "IN2")
		(18 "In8.Cu" signal "GND3")
		(20 "In9.Cu" signal "IN3")
		(22 "In10.Cu" signal "GND4")
		(24 "In11.Cu" signal "IN4")
		(26 "In12.Cu" signal "GND5")
		(28 "In13.Cu" signal "IN5")
		(30 "In14.Cu" signal "GND6")
		(32 "In15.Cu" signal "IN6")
		(34 "In16.Cu" signal "GND7")
		(2 "B.Cu" signal "BOTTOM")
		(9 "F.Adhes" user "F.Adhesive")
		(11 "B.Adhes" user "B.Adhesive")
		(13 "F.Paste" user "Package Geometry/Pastemask Top")
		(15 "B.Paste" user "Package Geometry/Pastemask Bottom")
		(5 "F.SilkS" user "Ref Des/Silkscreen Top")
		(7 "B.SilkS" user "Ref Des/Silkscreen Bottom")
		(1 "F.Mask" user "Board Geometry/Soldermask Top")
		(3 "B.Mask" user "Board Geometry/Soldermask Bottom")
		(17 "Dwgs.User" user "User.Drawings")
		(19 "Cmts.User" user "User.Comments")
		(21 "Eco1.User" user "User.Eco1")
		(23 "Eco2.User" user "User.Eco2")
		(25 "Edge.Cuts" user "Board Geometry/Outline")
		(27 "Margin" user)
		(31 "F.CrtYd" user "Package Geometry/Place Bound Top")
		(29 "B.CrtYd" user "Package Geometry/Place Bound Bottom")
		(35 "F.Fab" user "Ref Des/Assembly Top")
		(33 "B.Fab" user "Ref Des/Assembly Bottom")
	)
	(footprint ""
		(layer "B.Cu")
		(at 75.716892 -295.42486)
		(property "Reference" "C2902"
			(at 0 0 0)
			(layer "B.SilkS")
			(hide yes)
			(effects
				(font
					(size 1.27 1.27)
				)
				(justify mirror)
			)
		)
		(property "Value" ""
			(at 0 0 0)
			(layer "B.Fab")
			(effects
				(font
					(size 1.27 1.27)
				)
				(justify mirror)
			)
		)
		(duplicate_pad_numbers_are_jumpers no)
		(fp_line
			(start -1.2954 -0.5842)
			(end -1.2954 0.5842)
			(stroke
				(width 0.1524)
				(type default)
			)
			(layer "B.SilkS")
		)
		(fp_line
			(start -1.2954 0.5842)
			(end 1.2954 0.5842)
			(stroke
				(width 0.1524)
				(type default)
			)
			(layer "B.SilkS")
		)
		(fp_line
			(start 1.2954 -0.5842)
			(end -1.2954 -0.5842)
			(stroke
				(width 0.1524)
				(type default)
			)
			(layer "B.SilkS")
		)
		(fp_line
			(start 1.2954 0.5842)
			(end 1.2954 -0.5842)
			(stroke
				(width 0.1524)
				(type default)
			)
			(layer "B.SilkS")
		)
		(fp_line
			(start -1.1938 -0.4064)
			(end -1.1938 0.4064)
			(stroke
				(width 0.1)
				(type default)
			)
			(layer "B.Fab")
		)
		(fp_line
			(start -1.1938 0.4064)
			(end -0.8636 0.4064)
			(stroke
				(width 0.1)
				(type default)
			)
			(layer "B.Fab")
		)
		(fp_line
			(start -0.8636 -0.4572)
			(end -0.8636 -0.4064)
			(stroke
				(width 0.1)
				(type default)
			)
			(layer "B.Fab")
		)
		(fp_line
			(start -0.8636 -0.4064)
			(end -1.1938 -0.4064)
			(stroke
				(width 0.1)
				(type default)
			)
			(layer "B.Fab")
		)
		(fp_line
			(start -0.8636 0.4064)
			(end -0.8636 0.4572)
			(stroke
				(width 0.1)
				(type default)
			)
			(layer "B.Fab")
		)
		(fp_line
			(start -0.8636 0.4572)
			(end 0.8636 0.4572)
			(stroke
				(width 0.1)
				(type default)
			)
			(layer "B.Fab")
		)
		(fp_line
			(start 0.8636 -0.4572)
			(end -0.8636 -0.4572)
			(stroke
				(width 0.1)
				(type default)
			)
			(layer "B.Fab")
		)
		(fp_line
			(start 0.8636 -0.4064)
			(end 0.8636 -0.4572)
			(stroke
				(width 0.1)
				(type default)
			)
			(layer "B.Fab")
		)
		(fp_line
			(start 0.8636 0.4064)
			(end 1.1938 0.4064)
			(stroke
				(width 0.1)
				(type default)
			)
			(layer "B.Fab")
		)
		(fp_line
			(start 0.8636 0.4572)
			(end 0.8636 0.4064)
			(stroke
				(width 0.1)
				(type default)
			)
			(layer "B.Fab")
		)
		(fp_line
			(start 1.1938 -0.4064)
			(end 0.8636 -0.4064)
			(stroke
				(width 0.1)
				(type default)
			)
			(layer "B.Fab")
		)
		(fp_line
			(start 1.1938 0.4064)
			(end 1.1938 -0.4064)
			(stroke
				(width 0.1)
				(type default)
			)
			(layer "B.Fab")
		)
		(pad "1" smd rect
			(at 0.7366 0 270)
			(size 0.7112 0.8128)
			(layers "B.Cu" "B.Mask" "B.Paste")
			(net "P1V25_PEX0")
		)
		(pad "2" smd rect
			(at -0.7366 0 270)
			(size 0.7112 0.8128)
			(layers "B.Cu" "B.Mask" "B.Paste")
			(net "GND")
		)
	)
	(footprint ""
		(layer "B.Cu")
		(at 279.977342 -299.5422 90)
		(property "Reference" "C3371"
			(at 0 0 90)
			(layer "B.SilkS")
			(hide yes)
			(effects
				(font
					(size 1.27 1.27)
				)
				(justify mirror)
			)
		)
		(property "Value" ""
			(at 0 0 90)
			(layer "B.Fab")
			(effects
				(font
					(size 1.27 1.27)
				)
				(justify mirror)
			)
		)
		(duplicate_pad_numbers_are_jumpers no)
		(fp_line
			(start 0.299974 -0.150114)
			(end -0.299974 -0.150114)
			(stroke
				(width 0.1)
				(type default)
			)
			(layer "B.Fab")
		)
		(fp_line
			(start -0.299974 -0.150114)
			(end -0.299974 0.150114)
			(stroke
				(width 0.1)
				(type default)
			)
			(layer "B.Fab")
		)
		(fp_line
			(start 0.299974 0.150114)
			(end 0.299974 -0.150114)
			(stroke
				(width 0.1)
				(type default)
			)
			(layer "B.Fab")
		)
		(fp_line
			(start -0.299974 0.150114)
			(end 0.299974 0.150114)
			(stroke
				(width 0.1)
				(type default)
			)
			(layer "B.Fab")
		)
		(pad "1" smd rect
			(at 0.2667 0 270)
			(size 0.3048 0.381)
			(layers "B.Cu" "B.Mask" "B.Paste")
			(net "PCEPLL0_VDDA18_PEX2")
		)
		(pad "2" smd rect
			(at -0.2667 0 270)
			(size 0.3048 0.381)
			(layers "B.Cu" "B.Mask" "B.Paste")
			(net "GND")
		)
	)
	(footprint ""
		(layer "B.Cu")
		(at 363.710474 -282.244038 180)
		(property "Reference" "PR7174"
			(at 0 0 0)
			(layer "B.SilkS")
			(hide yes)
			(effects
				(font
					(size 1.27 1.27)
				)
				(justify mirror)
			)
		)
		(property "Value" ""
			(at 0 0 0)
			(layer "B.Fab")
			(effects
				(font
					(size 1.27 1.27)
				)
				(justify mirror)
			)
		)
		(duplicate_pad_numbers_are_jumpers no)
		(fp_line
			(start 0.7874 0.4064)
			(end 0.7874 -0.4064)
			(stroke
				(width 0.1524)
				(type default)
			)
			(layer "B.SilkS")
		)
		(fp_line
			(start 0.7874 -0.4064)
			(end -0.7874 -0.4064)
			(stroke
				(width 0.1524)
				(type default)
			)
			(layer "B.SilkS")
		)
		(fp_line
			(start -0.7874 0.4064)
			(end 0.7874 0.4064)
			(stroke
				(width 0.1524)
				(type default)
			)
			(layer "B.SilkS")
		)
		(fp_line
			(start -0.7874 -0.4064)
			(end -0.7874 0.4064)
			(stroke
				(width 0.1524)
				(type default)
			)
			(layer "B.SilkS")
		)
		(fp_line
			(start 0.67945 0.3048)
			(end 0.67945 -0.305054)
			(stroke
				(width 0.1)
				(type default)
			)
			(layer "B.Fab")
		)
		(fp_line
			(start 0.67945 -0.305054)
			(end 0.12065 -0.305054)
			(stroke
				(width 0.1)
				(type default)
			)
			(layer "B.Fab")
		)
		(fp_line
			(start 0.12065 0.3048)
			(end 0.67945 0.3048)
			(stroke
				(width 0.1)
				(type default)
			)
			(layer "B.Fab")
		)
		(fp_line
			(start 0.12065 0.2794)
			(end 0.12065 0.3048)
			(stroke
				(width 0.1)
				(type default)
			)
			(layer "B.Fab")
		)
		(fp_line
			(start 0.12065 -0.2794)
			(end -0.12065 -0.2794)
			(stroke
				(width 0.1)
				(type default)
			)
			(layer "B.Fab")
		)
		(fp_line
			(start 0.12065 -0.305054)
			(end 0.12065 -0.2794)
			(stroke
				(width 0.1)
				(type default)
			)
			(layer "B.Fab")
		)
		(fp_line
			(start -0.120396 0.3048)
			(end -0.120396 0.2794)
			(stroke
				(width 0.1)
				(type default)
			)
			(layer "B.Fab")
		)
		(fp_line
			(start -0.120396 0.2794)
			(end 0.12065 0.2794)
			(stroke
				(width 0.1)
				(type default)
			)
			(layer "B.Fab")
		)
		(fp_line
			(start -0.12065 -0.2794)
			(end -0.12065 -0.3048)
			(stroke
				(width 0.1)
				(type default)
			)
			(layer "B.Fab")
		)
		(fp_line
			(start -0.12065 -0.3048)
			(end -0.67945 -0.3048)
			(stroke
				(width 0.1)
				(type default)
			)
			(layer "B.Fab")
		)
		(fp_line
			(start -0.67945 0.3048)
			(end -0.120396 0.3048)
			(stroke
				(width 0.1)
				(type default)
			)
			(layer "B.Fab")
		)
		(fp_line
			(start -0.67945 -0.3048)
			(end -0.67945 0.3048)
			(stroke
				(width 0.1)
				(type default)
			)
			(layer "B.Fab")
		)
		(pad "1" smd circle
			(at 0.40005 0)
			(size 0 0)
			(layers "B.Cu" "B.Mask" "B.Paste")
			(net "P0V8_PEX2_EN4")
		)
		(pad "2" smd circle
			(at -0.40005 0)
			(size 0 0)
			(layers "B.Cu" "B.Mask" "B.Paste")
			(net "P0V8_PEX3_VCC2")
		)
	)
	(footprint ""
		(layer "B.Cu")
		(at 222.212154 -193.759836 90)
		(property "Reference" "R467"
			(at 0 0 90)
			(layer "B.SilkS")
			(hide yes)
			(effects
				(font
					(size 1.27 1.27)
				)
				(justify mirror)
			)
		)
		(property "Value" ""
			(at 0 0 90)
			(layer "B.Fab")
			(effects
				(font
					(size 1.27 1.27)
				)
				(justify mirror)
			)
		)
		(duplicate_pad_numbers_are_jumpers no)
		(fp_line
			(start 0.7874 -0.4064)
			(end -0.7874 -0.4064)
			(stroke
				(width 0.1524)
				(type default)
			)
			(layer "B.SilkS")
		)
		(fp_line
			(start -0.7874 -0.4064)
			(end -0.7874 0.4064)
			(stroke
				(width 0.1524)
				(type default)
			)
			(layer "B.SilkS")
		)
		(fp_line
			(start 0.7874 0.4064)
			(end 0.7874 -0.4064)
			(stroke
				(width 0.1524)
				(type default)
			)
			(layer "B.SilkS")
		)
		(fp_line
			(start -0.7874 0.4064)
			(end 0.7874 0.4064)
			(stroke
				(width 0.1524)
				(type default)
			)
			(layer "B.SilkS")
		)
		(fp_line
			(start 0.67945 -0.305054)
			(end 0.12065 -0.305054)
			(stroke
				(width 0.1)
				(type default)
			)
			(layer "B.Fab")
		)
		(fp_line
			(start 0.12065 -0.305054)
			(end 0.12065 -0.2794)
			(stroke
				(width 0.1)
				(type default)
			)
			(layer "B.Fab")
		)
		(fp_line
			(start -0.12065 -0.3048)
			(end -0.67945 -0.3048)
			(stroke
				(width 0.1)
				(type default)
			)
			(layer "B.Fab")
		)
		(fp_line
			(start -0.67945 -0.3048)
			(end -0.67945 0.3048)
			(stroke
				(width 0.1)
				(type default)
			)
			(layer "B.Fab")
		)
		(fp_line
			(start 0.12065 -0.2794)
			(end -0.12065 -0.2794)
			(stroke
				(width 0.1)
				(type default)
			)
			(layer "B.Fab")
		)
		(fp_line
			(start -0.12065 -0.2794)
			(end -0.12065 -0.3048)
			(stroke
				(width 0.1)
				(type default)
			)
			(layer "B.Fab")
		)
		(fp_line
			(start 0.12065 0.2794)
			(end 0.12065 0.3048)
			(stroke
				(width 0.1)
				(type default)
			)
			(layer "B.Fab")
		)
		(fp_line
			(start -0.120396 0.2794)
			(end 0.12065 0.2794)
			(stroke
				(width 0.1)
				(type default)
			)
			(layer "B.Fab")
		)
		(fp_line
			(start 0.67945 0.3048)
			(end 0.67945 -0.305054)
			(stroke
				(width 0.1)
				(type default)
			)
			(layer "B.Fab")
		)
		(fp_line
			(start 0.12065 0.3048)
			(end 0.67945 0.3048)
			(stroke
				(width 0.1)
				(type default)
			)
			(layer "B.Fab")
		)
		(fp_line
			(start -0.120396 0.3048)
			(end -0.120396 0.2794)
			(stroke
				(width 0.1)
				(type default)
			)
			(layer "B.Fab")
		)
		(fp_line
			(start -0.67945 0.3048)
			(end -0.120396 0.3048)
			(stroke
				(width 0.1)
				(type default)
			)
			(layer "B.Fab")
		)
		(pad "1" smd circle
			(at 0.40005 0 270)
			(size 0 0)
			(layers "B.Cu" "B.Mask" "B.Paste")
			(net "SPI_BIC1_MOSI_R1")
		)
		(pad "2" smd circle
			(at -0.40005 0 270)
			(size 0 0)
			(layers "B.Cu" "B.Mask" "B.Paste")
			(net "SPI_BIC1_MOSI_R2")
		)
	)
	(footprint ""
		(layer "B.Cu")
		(at 354.588318 -249.945398 180)
		(property "Reference" "R6715"
			(at 0 0 0)
			(layer "B.SilkS")
			(hide yes)
			(effects
				(font
					(size 1.27 1.27)
				)
				(justify mirror)
			)
		)
		(property "Value" ""
			(at 0 0 0)
			(layer "B.Fab")
			(effects
				(font
					(size 1.27 1.27)
				)
				(justify mirror)
			)
		)
		(duplicate_pad_numbers_are_jumpers no)
		(fp_line
			(start 0.7874 0.4064)
			(end 0.7874 -0.4064)
			(stroke
				(width 0.1524)
				(type default)
			)
			(layer "B.SilkS")
		)
		(fp_line
			(start 0.7874 -0.4064)
			(end -0.7874 -0.4064)
			(stroke
				(width 0.1524)
				(type default)
			)
			(layer "B.SilkS")
		)
		(fp_line
			(start -0.7874 0.4064)
			(end 0.7874 0.4064)
			(stroke
				(width 0.1524)
				(type default)
			)
			(layer "B.SilkS")
		)
		(fp_line
			(start -0.7874 -0.4064)
			(end -0.7874 0.4064)
			(stroke
				(width 0.1524)
				(type default)
			)
			(layer "B.SilkS")
		)
		(fp_line
			(start 0.67945 0.3048)
			(end 0.67945 -0.305054)
			(stroke
				(width 0.1)
				(type default)
			)
			(layer "B.Fab")
		)
		(fp_line
			(start 0.67945 -0.305054)
			(end 0.12065 -0.305054)
			(stroke
				(width 0.1)
				(type default)
			)
			(layer "B.Fab")
		)
		(fp_line
			(start 0.12065 0.3048)
			(end 0.67945 0.3048)
			(stroke
				(width 0.1)
				(type default)
			)
			(layer "B.Fab")
		)
		(fp_line
			(start 0.12065 0.2794)
			(end 0.12065 0.3048)
			(stroke
				(width 0.1)
				(type default)
			)
			(layer "B.Fab")
		)
		(fp_line
			(start 0.12065 -0.2794)
			(end -0.12065 -0.2794)
			(stroke
				(width 0.1)
				(type default)
			)
			(layer "B.Fab")
		)
		(fp_line
			(start 0.12065 -0.305054)
			(end 0.12065 -0.2794)
			(stroke
				(width 0.1)
				(type default)
			)
			(layer "B.Fab")
		)
		(fp_line
			(start -0.120396 0.3048)
			(end -0.120396 0.2794)
			(stroke
				(width 0.1)
				(type default)
			)
			(layer "B.Fab")
		)
		(fp_line
			(start -0.120396 0.2794)
			(end 0.12065 0.2794)
			(stroke
				(width 0.1)
				(type default)
			)
			(layer "B.Fab")
		)
		(fp_line
			(start -0.12065 -0.2794)
			(end -0.12065 -0.3048)
			(stroke
				(width 0.1)
				(type default)
			)
			(layer "B.Fab")
		)
		(fp_line
			(start -0.12065 -0.3048)
			(end -0.67945 -0.3048)
			(stroke
				(width 0.1)
				(type default)
			)
			(layer "B.Fab")
		)
		(fp_line
			(start -0.67945 0.3048)
			(end -0.120396 0.3048)
			(stroke
				(width 0.1)
				(type default)
			)
			(layer "B.Fab")
		)
		(fp_line
			(start -0.67945 -0.3048)
			(end -0.67945 0.3048)
			(stroke
				(width 0.1)
				(type default)
			)
			(layer "B.Fab")
		)
		(pad "1" smd circle
			(at 0.40005 0)
			(size 0 0)
			(layers "B.Cu" "B.Mask" "B.Paste")
			(net "SMB_SML1_PMBUS_HSC_SDA")
		)
		(pad "2" smd circle
			(at -0.40005 0)
			(size 0 0)
			(layers "B.Cu" "B.Mask" "B.Paste")
			(net "SMB_BIC_I2C6_MUX_VR_R_SDA")
		)
	)
	(footprint ""
		(layer "B.Cu")
		(at 403.674834 -293.99992 -90)
		(property "Reference" "C1918"
			(at 0 0 90)
			(layer "B.SilkS")
			(hide yes)
			(effects
				(font
					(size 1.27 1.27)
				)
				(justify mirror)
			)
		)
		(property "Value" ""
			(at 0 0 90)
			(layer "B.Fab")
			(effects
				(font
					(size 1.27 1.27)
				)
				(justify mirror)
			)
		)
		(duplicate_pad_numbers_are_jumpers no)
		(fp_line
			(start -0.299974 0.150114)
			(end 0.299974 0.150114)
			(stroke
				(width 0.1)
				(type default)
			)
			(layer "B.Fab")
		)
		(fp_line
			(start 0.299974 0.150114)
			(end 0.299974 -0.150114)
			(stroke
				(width 0.1)
				(type default)
			)
			(layer "B.Fab")
		)
		(fp_line
			(start -0.299974 -0.150114)
			(end -0.299974 0.150114)
			(stroke
				(width 0.1)
				(type default)
			)
			(layer "B.Fab")
		)
		(fp_line
			(start 0.299974 -0.150114)
			(end -0.299974 -0.150114)
			(stroke
				(width 0.1)
				(type default)
			)
			(layer "B.Fab")
		)
		(pad "1" smd rect
			(at 0.2667 0 90)
			(size 0.3048 0.381)
			(layers "B.Cu" "B.Mask" "B.Paste")
			(net "P0V8_PEX3")
		)
		(pad "2" smd rect
			(at -0.2667 0 90)
			(size 0.3048 0.381)
			(layers "B.Cu" "B.Mask" "B.Paste")
			(net "GND")
		)
	)
	(footprint ""
		(layer "B.Cu")
		(at 287.099756 -290.199826 90)
		(property "Reference" "C1746"
			(at 0 0 90)
			(layer "B.SilkS")
			(hide yes)
			(effects
				(font
					(size 1.27 1.27)
				)
				(justify mirror)
			)
		)
		(property "Value" ""
			(at 0 0 90)
			(layer "B.Fab")
			(effects
				(font
					(size 1.27 1.27)
				)
				(justify mirror)
			)
		)
		(duplicate_pad_numbers_are_jumpers no)
		(fp_line
			(start 0.299974 -0.150114)
			(end -0.299974 -0.150114)
			(stroke
				(width 0.1)
				(type default)
			)
			(layer "B.Fab")
		)
		(fp_line
			(start -0.299974 -0.150114)
			(end -0.299974 0.150114)
			(stroke
				(width 0.1)
				(type default)
			)
			(layer "B.Fab")
		)
		(fp_line
			(start 0.299974 0.150114)
			(end 0.299974 -0.150114)
			(stroke
				(width 0.1)
				(type default)
			)
			(layer "B.Fab")
		)
		(fp_line
			(start -0.299974 0.150114)
			(end 0.299974 0.150114)
			(stroke
				(width 0.1)
				(type default)
			)
			(layer "B.Fab")
		)
		(pad "1" smd rect
			(at 0.2667 0 270)
			(size 0.3048 0.381)
			(layers "B.Cu" "B.Mask" "B.Paste")
			(net "P0V8_SERDES_VDDA_PEX2")
		)
		(pad "2" smd rect
			(at -0.2667 0 270)
			(size 0.3048 0.381)
			(layers "B.Cu" "B.Mask" "B.Paste")
			(net "GND")
		)
	)
	(footprint ""
		(layer "B.Cu")
		(at 100.358194 -379.090174 -90)
		(property "Reference" "R1836"
			(at 0 0 90)
			(layer "B.SilkS")
			(hide yes)
			(effects
				(font
					(size 1.27 1.27)
				)
				(justify mirror)
			)
		)
		(property "Value" ""
			(at 0 0 90)
			(layer "B.Fab")
			(effects
				(font
					(size 1.27 1.27)
				)
				(justify mirror)
			)
		)
		(duplicate_pad_numbers_are_jumpers no)
		(fp_line
			(start -0.7874 0.4064)
			(end 0.7874 0.4064)
			(stroke
				(width 0.1524)
				(type default)
			)
			(layer "B.SilkS")
		)
		(fp_line
			(start 0.7874 0.4064)
			(end 0.7874 -0.4064)
			(stroke
				(width 0.1524)
				(type default)
			)
			(layer "B.SilkS")
		)
		(fp_line
			(start -0.7874 -0.4064)
			(end -0.7874 0.4064)
			(stroke
				(width 0.1524)
				(type default)
			)
			(layer "B.SilkS")
		)
		(fp_line
			(start 0.7874 -0.4064)
			(end -0.7874 -0.4064)
			(stroke
				(width 0.1524)
				(type default)
			)
			(layer "B.SilkS")
		)
		(fp_line
			(start -0.67945 0.3048)
			(end -0.120396 0.3048)
			(stroke
				(width 0.1)
				(type default)
			)
			(layer "B.Fab")
		)
		(fp_line
			(start -0.120396 0.3048)
			(end -0.120396 0.2794)
			(stroke
				(width 0.1)
				(type default)
			)
			(layer "B.Fab")
		)
		(fp_line
			(start 0.12065 0.3048)
			(end 0.67945 0.3048)
			(stroke
				(width 0.1)
				(type default)
			)
			(layer "B.Fab")
		)
		(fp_line
			(start 0.67945 0.3048)
			(end 0.67945 -0.305054)
			(stroke
				(width 0.1)
				(type default)
			)
			(layer "B.Fab")
		)
		(fp_line
			(start -0.120396 0.2794)
			(end 0.12065 0.2794)
			(stroke
				(width 0.1)
				(type default)
			)
			(layer "B.Fab")
		)
		(fp_line
			(start 0.12065 0.2794)
			(end 0.12065 0.3048)
			(stroke
				(width 0.1)
				(type default)
			)
			(layer "B.Fab")
		)
		(fp_line
			(start -0.12065 -0.2794)
			(end -0.12065 -0.3048)
			(stroke
				(width 0.1)
				(type default)
			)
			(layer "B.Fab")
		)
		(fp_line
			(start 0.12065 -0.2794)
			(end -0.12065 -0.2794)
			(stroke
				(width 0.1)
				(type default)
			)
			(layer "B.Fab")
		)
		(fp_line
			(start -0.67945 -0.3048)
			(end -0.67945 0.3048)
			(stroke
				(width 0.1)
				(type default)
			)
			(layer "B.Fab")
		)
		(fp_line
			(start -0.12065 -0.3048)
			(end -0.67945 -0.3048)
			(stroke
				(width 0.1)
				(type default)
			)
			(layer "B.Fab")
		)
		(fp_line
			(start 0.12065 -0.305054)
			(end 0.12065 -0.2794)
			(stroke
				(width 0.1)
				(type default)
			)
			(layer "B.Fab")
		)
		(fp_line
			(start 0.67945 -0.305054)
			(end 0.12065 -0.305054)
			(stroke
				(width 0.1)
				(type default)
			)
			(layer "B.Fab")
		)
		(pad "1" smd circle
			(at 0.40005 0 90)
			(size 0 0)
			(layers "B.Cu" "B.Mask" "B.Paste")
			(net "SMB_GPU_1_R_SDA")
		)
		(pad "2" smd circle
			(at -0.40005 0 90)
			(size 0 0)
			(layers "B.Cu" "B.Mask" "B.Paste")
			(net "SMB_GPU_1_SDA")
		)
	)
)
